(kicad_pcb
	(version 20260206)
	(generator "pcbnew")
	(generator_version "10.0")
	(general
		(thickness 1.6)
		(legacy_teardrops no)
	)
	(paper "A4")
	(title_block
		(title "timecard-production-celestica-r4006 — R4006-B0001-02_R01.brd")
		(comment 1 "Time Appliance Project (Time Card) / footprints 940-944 of 1113")
	)
	(layers
		(0 "F.Cu" signal "TOP")
		(4 "In1.Cu" signal "L02_GND1")
		(6 "In2.Cu" signal "L03_SIG1")
		(8 "In3.Cu" signal "L04_GND2")
		(10 "In4.Cu" signal "L05_VCC1")
		(12 "In5.Cu" signal "L06_VCC2")
		(14 "In6.Cu" signal "L07_GND3")
		(16 "In7.Cu" signal "L08_SIG2")
		(18 "In8.Cu" signal "L09_GND4")
		(2 "B.Cu" signal "BOTTOM")
		(9 "F.Adhes" user "F.Adhesive")
		(11 "B.Adhes" user "B.Adhesive")
		(13 "F.Paste" user "Package Geometry/Pastemask Top")
		(15 "B.Paste" user "Package Geometry/Pastemask Bottom")
		(5 "F.SilkS" user "Ref Des/Silkscreen Top")
		(7 "B.SilkS" user "Ref Des/Silkscreen Bottom")
		(1 "F.Mask" user "Board Geometry/Soldermask Top")
		(3 "B.Mask" user "Board Geometry/Soldermask Bottom")
		(17 "Dwgs.User" user "User.Drawings")
		(19 "Cmts.User" user "User.Comments")
		(21 "Eco1.User" user "User.Eco1")
		(23 "Eco2.User" user "User.Eco2")
		(25 "Edge.Cuts" user "Board Geometry/Outline")
		(27 "Margin" user)
		(31 "F.CrtYd" user "Package Geometry/Place Bound Top")
		(29 "B.CrtYd" user "Package Geometry/Place Bound Bottom")
		(35 "F.Fab" user "Ref Des/Assembly Top")
		(33 "B.Fab" user "Ref Des/Assembly Bottom")
	)
	(footprint ""
		(layer "B.Cu")
		(at 17.6784 -39.2176 180)
		(property "Reference" "R145"
			(at 0.4064 -2.55397 0)
			(unlocked yes)
			(layer "B.SilkS")
			(effects
				(font
					(size 0.7874 0.5842)
					(thickness 0.1524)
				)
				(justify mirror)
			)
		)
		(property "Value" "VAL*"
			(at -0.02032 2.13233 180)
			(unlocked yes)
			(layer "B.Fab")
			(hide yes)
			(effects
				(font
					(size 0.7874 0.5842)
					(thickness 0.1524)
				)
				(justify mirror)
			)
		)
		(property "Device Type" "RESISTOR-G155-133R0-01,33OHM,1%"
			(at -0.008382 1.210564 180)
			(unlocked yes)
			(layer "B.Fab")
			(hide yes)
			(effects
				(font
					(size 0.7874 0.5842)
					(thickness 0.1524)
				)
				(justify mirror)
			)
		)
		(property "User Part Number" "PARTNUM*"
			(at -0.02032 4.024884 180)
			(unlocked yes)
			(layer "Cmts.User")
			(hide yes)
			(effects
				(font
					(size 0.7874 0.5842)
					(thickness 0.1524)
				)
				(justify mirror)
			)
		)
		(property "Tolerance" "TOL*"
			(at -0.044704 3.05435 180)
			(unlocked yes)
			(layer "Cmts.User")
			(hide yes)
			(effects
				(font
					(size 0.7874 0.5842)
					(thickness 0.1524)
				)
				(justify mirror)
			)
		)
		(duplicate_pad_numbers_are_jumpers no)
		(fp_line
			(start 1.143 0.5588)
			(end -1.143 0.5588)
			(stroke
				(width 0.1)
				(type default)
			)
			(layer "B.SilkS")
		)
		(fp_line
			(start 1.143 -0.5588)
			(end 1.143 0.5588)
			(stroke
				(width 0.1)
				(type default)
			)
			(layer "B.SilkS")
		)
		(fp_line
			(start -1.143 0.5588)
			(end -1.143 -0.5588)
			(stroke
				(width 0.1)
				(type default)
			)
			(layer "B.SilkS")
		)
		(fp_line
			(start -1.143 -0.5588)
			(end 1.143 -0.5588)
			(stroke
				(width 0.1)
				(type default)
			)
			(layer "B.SilkS")
		)
		(fp_rect
			(start 1.143 0.5588)
			(end -1.143 -0.5588)
			(stroke
				(width 0)
				(type default)
			)
			(fill no)
			(layer "B.CrtYd")
		)
		(fp_line
			(start 0.508 0.3048)
			(end -0.508 0.3048)
			(stroke
				(width 0.1)
				(type default)
			)
			(layer "B.Fab")
		)
		(fp_line
			(start 0.508 -0.3048)
			(end 0.508 0.3048)
			(stroke
				(width 0.1)
				(type default)
			)
			(layer "B.Fab")
		)
		(fp_line
			(start -0.508 0.3048)
			(end -0.508 -0.3048)
			(stroke
				(width 0.1)
				(type default)
			)
			(layer "B.Fab")
		)
		(fp_line
			(start -0.508 -0.3048)
			(end 0.508 -0.3048)
			(stroke
				(width 0.1)
				(type default)
			)
			(layer "B.Fab")
		)
		(pad "1" smd rect
			(at 0.5334 0)
			(size 0.7112 0.6096)
			(layers "B.Cu" "B.Mask" "B.Paste")
			(net "PCA9546_I2C_SCL")
		)
		(pad "2" smd rect
			(at -0.5334 0)
			(size 0.7112 0.6096)
			(layers "B.Cu" "B.Mask" "B.Paste")
			(net "R_PCA9546_I2C_SCL")
		)
		(zone
			(layer "B.Cu")
			(hatch none 0.5)
			(connect_pads
				(clearance 0)
			)
			(min_thickness 0.25)
			(keepout
				(tracks allowed)
				(vias not_allowed)
				(pads allowed)
				(copperpour not_allowed)
				(footprints allowed)
			)
			(placement
				(enabled no)
				(sheetname "")
			)
			(fill
				(thermal_gap 0.5)
				(thermal_bridge_width 0.5)
				(island_removal_mode 0)
			)
			(polygon
				(pts
					(xy 17.6022 -39.5224) (xy 17.6022 -38.9128) (xy 17.7546 -38.9128) (xy 17.7546 -39.5224)
				)
			)
		)
	)
	(footprint ""
		(layer "B.Cu")
		(at 98.17862 -44.323)
		(property "Reference" "C104"
			(at -0.13462 -1.42875 0)
			(unlocked yes)
			(layer "B.SilkS")
			(effects
				(font
					(size 0.635 0.4064)
					(thickness 0.1524)
				)
				(justify mirror)
			)
		)
		(property "Value" "VAL*"
			(at -0.0762 2.067306 0)
			(unlocked yes)
			(layer "B.Fab")
			(hide yes)
			(effects
				(font
					(size 0.7874 0.5842)
					(thickness 0.1524)
				)
				(justify mirror)
			)
		)
		(property "Tolerance" "TOL*"
			(at -0.0762 3.032506 0)
			(unlocked yes)
			(layer "Cmts.User")
			(hide yes)
			(effects
				(font
					(size 0.7874 0.5842)
					(thickness 0.1524)
				)
				(justify mirror)
			)
		)
		(property "User Part Number" "PARTNUM*"
			(at -0.1016 4.023106 0)
			(unlocked yes)
			(layer "Cmts.User")
			(hide yes)
			(effects
				(font
					(size 0.7874 0.5842)
					(thickness 0.1524)
				)
				(justify mirror)
			)
		)
		(property "Device Type" "CAPACITOR-G105-0B104-CK,0.1UF,A"
			(at -0.0508 1.127506 0)
			(unlocked yes)
			(layer "B.Fab")
			(hide yes)
			(effects
				(font
					(size 0.7874 0.5842)
					(thickness 0.1524)
				)
				(justify mirror)
			)
		)
		(duplicate_pad_numbers_are_jumpers no)
		(fp_line
			(start -1.143 -0.5588)
			(end 1.143 -0.5588)
			(stroke
				(width 0.1)
				(type default)
			)
			(layer "B.SilkS")
		)
		(fp_line
			(start -1.143 0.5588)
			(end -1.143 -0.5588)
			(stroke
				(width 0.1)
				(type default)
			)
			(layer "B.SilkS")
		)
		(fp_line
			(start 1.143 -0.5588)
			(end 1.143 0.5588)
			(stroke
				(width 0.1)
				(type default)
			)
			(layer "B.SilkS")
		)
		(fp_line
			(start 1.143 0.5588)
			(end -1.143 0.5588)
			(stroke
				(width 0.1)
				(type default)
			)
			(layer "B.SilkS")
		)
		(fp_rect
			(start -1.143 0.5588)
			(end 1.143 -0.5588)
			(stroke
				(width 0)
				(type default)
			)
			(fill no)
			(layer "B.CrtYd")
		)
		(fp_line
			(start -0.508 -0.3048)
			(end 0.508 -0.3048)
			(stroke
				(width 0.1)
				(type default)
			)
			(layer "B.Fab")
		)
		(fp_line
			(start -0.508 0.3048)
			(end -0.508 -0.3048)
			(stroke
				(width 0.1)
				(type default)
			)
			(layer "B.Fab")
		)
		(fp_line
			(start 0.508 -0.3048)
			(end 0.508 0.3048)
			(stroke
				(width 0.1)
				(type default)
			)
			(layer "B.Fab")
		)
		(fp_line
			(start 0.508 0.3048)
			(end -0.508 0.3048)
			(stroke
				(width 0.1)
				(type default)
			)
			(layer "B.Fab")
		)
		(pad "1" smd rect
			(at 0.5334 0 180)
			(size 0.7112 0.6096)
			(layers "B.Cu" "B.Mask" "B.Paste")
			(net "FPGA_MGTAVTT")
		)
		(pad "2" smd rect
			(at -0.5334 0 180)
			(size 0.7112 0.6096)
			(layers "B.Cu" "B.Mask" "B.Paste")
			(net "SG")
		)
		(zone
			(layer "B.Cu")
			(hatch none 0.5)
			(connect_pads
				(clearance 0)
			)
			(min_thickness 0.25)
			(keepout
				(tracks allowed)
				(vias not_allowed)
				(pads allowed)
				(copperpour not_allowed)
				(footprints allowed)
			)
			(placement
				(enabled no)
				(sheetname "")
			)
			(fill
				(thermal_gap 0.5)
				(thermal_bridge_width 0.5)
				(island_removal_mode 0)
			)
			(polygon
				(pts
					(xy 98.10242 -44.0182) (xy 98.25482 -44.0182) (xy 98.25482 -44.6278) (xy 98.10242 -44.6278)
				)
			)
		)
	)
	(footprint ""
		(layer "B.Cu")
		(at 101.0412 -64.2874 90)
		(property "Reference" "R171"
			(at 3.4036 -0.24257 270)
			(unlocked yes)
			(layer "B.SilkS")
			(effects
				(font
					(size 0.7874 0.5842)
					(thickness 0.1524)
				)
				(justify mirror)
			)
		)
		(property "Value" "VAL*"
			(at -0.02032 2.13233 90)
			(unlocked yes)
			(layer "B.Fab")
			(hide yes)
			(effects
				(font
					(size 0.7874 0.5842)
					(thickness 0.1524)
				)
				(justify mirror)
			)
		)
		(property "Tolerance" "TOL*"
			(at -0.044704 3.05435 90)
			(unlocked yes)
			(layer "Cmts.User")
			(hide yes)
			(effects
				(font
					(size 0.7874 0.5842)
					(thickness 0.1524)
				)
				(justify mirror)
			)
		)
		(property "User Part Number" "PARTNUM*"
			(at -0.02032 4.024884 90)
			(unlocked yes)
			(layer "Cmts.User")
			(hide yes)
			(effects
				(font
					(size 0.7874 0.5842)
					(thickness 0.1524)
				)
				(justify mirror)
			)
		)
		(property "Device Type" "RESISTOR-G155-14701-01,4.7KOHMA"
			(at -0.008382 1.210564 90)
			(unlocked yes)
			(layer "B.Fab")
			(hide yes)
			(effects
				(font
					(size 0.7874 0.5842)
					(thickness 0.1524)
				)
				(justify mirror)
			)
		)
		(duplicate_pad_numbers_are_jumpers no)
		(fp_line
			(start 1.143 -0.5588)
			(end 1.143 0.5588)
			(stroke
				(width 0.1)
				(type default)
			)
			(layer "B.SilkS")
		)
		(fp_line
			(start -1.143 -0.5588)
			(end 1.143 -0.5588)
			(stroke
				(width 0.1)
				(type default)
			)
			(layer "B.SilkS")
		)
		(fp_line
			(start 1.143 0.5588)
			(end -1.143 0.5588)
			(stroke
				(width 0.1)
				(type default)
			)
			(layer "B.SilkS")
		)
		(fp_line
			(start -1.143 0.5588)
			(end -1.143 -0.5588)
			(stroke
				(width 0.1)
				(type default)
			)
			(layer "B.SilkS")
		)
		(fp_rect
			(start -1.143 0.5588)
			(end 1.143 -0.5588)
			(stroke
				(width 0)
				(type default)
			)
			(fill no)
			(layer "B.CrtYd")
		)
		(fp_line
			(start 0.508 -0.3048)
			(end 0.508 0.3048)
			(stroke
				(width 0.1)
				(type default)
			)
			(layer "B.Fab")
		)
		(fp_line
			(start -0.508 -0.3048)
			(end 0.508 -0.3048)
			(stroke
				(width 0.1)
				(type default)
			)
			(layer "B.Fab")
		)
		(fp_line
			(start 0.508 0.3048)
			(end -0.508 0.3048)
			(stroke
				(width 0.1)
				(type default)
			)
			(layer "B.Fab")
		)
		(fp_line
			(start -0.508 0.3048)
			(end -0.508 -0.3048)
			(stroke
				(width 0.1)
				(type default)
			)
			(layer "B.Fab")
		)
		(pad "1" smd rect
			(at 0.5334 0 270)
			(size 0.7112 0.6096)
			(layers "B.Cu" "B.Mask" "B.Paste")
			(net "SG")
		)
		(pad "2" smd rect
			(at -0.5334 0 270)
			(size 0.7112 0.6096)
			(layers "B.Cu" "B.Mask" "B.Paste")
			(net "FPGA_IO_0")
		)
		(zone
			(layer "B.Cu")
			(hatch none 0.5)
			(connect_pads
				(clearance 0)
			)
			(min_thickness 0.25)
			(keepout
				(tracks allowed)
				(vias not_allowed)
				(pads allowed)
				(copperpour not_allowed)
				(footprints allowed)
			)
			(placement
				(enabled no)
				(sheetname "")
			)
			(fill
				(thermal_gap 0.5)
				(thermal_bridge_width 0.5)
				(island_removal_mode 0)
			)
			(polygon
				(pts
					(xy 101.346 -64.2112) (xy 101.346 -64.3636) (xy 100.7364 -64.3636) (xy 100.7364 -64.2112)
				)
			)
		)
	)
	(footprint ""
		(layer "B.Cu")
		(at 73.66 -72.771 -90)
		(property "Reference" "C60"
			(at -3.81 -0.59563 270)
			(unlocked yes)
			(layer "B.SilkS")
			(effects
				(font
					(size 0.7874 0.5842)
					(thickness 0.1524)
				)
				(justify mirror)
			)
		)
		(property "Value" "VAL*"
			(at -0.0762 2.067306 270)
			(unlocked yes)
			(layer "B.Fab")
			(hide yes)
			(effects
				(font
					(size 0.7874 0.5842)
					(thickness 0.1524)
				)
				(justify mirror)
			)
		)
		(property "Tolerance" "TOL*"
			(at -0.0762 3.032506 270)
			(unlocked yes)
			(layer "Cmts.User")
			(hide yes)
			(effects
				(font
					(size 0.7874 0.5842)
					(thickness 0.1524)
				)
				(justify mirror)
			)
		)
		(property "User Part Number" "PARTNUM*"
			(at -0.1016 4.023106 270)
			(unlocked yes)
			(layer "Cmts.User")
			(hide yes)
			(effects
				(font
					(size 0.7874 0.5842)
					(thickness 0.1524)
				)
				(justify mirror)
			)
		)
		(property "Device Type" "CAPACITOR-G105-0B104-EK,0.1UF,A"
			(at -0.0508 1.127506 270)
			(unlocked yes)
			(layer "B.Fab")
			(hide yes)
			(effects
				(font
					(size 0.7874 0.5842)
					(thickness 0.1524)
				)
				(justify mirror)
			)
		)
		(duplicate_pad_numbers_are_jumpers no)
		(fp_line
			(start -1.143 0.5588)
			(end -1.143 -0.5588)
			(stroke
				(width 0.1)
				(type default)
			)
			(layer "B.SilkS")
		)
		(fp_line
			(start 1.143 0.5588)
			(end -1.143 0.5588)
			(stroke
				(width 0.1)
				(type default)
			)
			(layer "B.SilkS")
		)
		(fp_line
			(start -1.143 -0.5588)
			(end 1.143 -0.5588)
			(stroke
				(width 0.1)
				(type default)
			)
			(layer "B.SilkS")
		)
		(fp_line
			(start 1.143 -0.5588)
			(end 1.143 0.5588)
			(stroke
				(width 0.1)
				(type default)
			)
			(layer "B.SilkS")
		)
		(fp_rect
			(start 1.143 -0.5588)
			(end -1.143 0.5588)
			(stroke
				(width 0)
				(type default)
			)
			(fill no)
			(layer "B.CrtYd")
		)
		(fp_line
			(start -0.508 0.3048)
			(end -0.508 -0.3048)
			(stroke
				(width 0.1)
				(type default)
			)
			(layer "B.Fab")
		)
		(fp_line
			(start 0.508 0.3048)
			(end -0.508 0.3048)
			(stroke
				(width 0.1)
				(type default)
			)
			(layer "B.Fab")
		)
		(fp_line
			(start -0.508 -0.3048)
			(end 0.508 -0.3048)
			(stroke
				(width 0.1)
				(type default)
			)
			(layer "B.Fab")
		)
		(fp_line
			(start 0.508 -0.3048)
			(end 0.508 0.3048)
			(stroke
				(width 0.1)
				(type default)
			)
			(layer "B.Fab")
		)
		(pad "1" smd rect
			(at 0.5334 0 90)
			(size 0.7112 0.6096)
			(layers "B.Cu" "B.Mask" "B.Paste")
			(net "XP5R0V_MAC")
		)
		(pad "2" smd rect
			(at -0.5334 0 90)
			(size 0.7112 0.6096)
			(layers "B.Cu" "B.Mask" "B.Paste")
			(net "SG")
		)
		(zone
			(layer "B.Cu")
			(hatch none 0.5)
			(connect_pads
				(clearance 0)
			)
			(min_thickness 0.25)
			(keepout
				(tracks allowed)
				(vias not_allowed)
				(pads allowed)
				(copperpour not_allowed)
				(footprints allowed)
			)
			(placement
				(enabled no)
				(sheetname "")
			)
			(fill
				(thermal_gap 0.5)
				(thermal_bridge_width 0.5)
				(island_removal_mode 0)
			)
			(polygon
				(pts
					(xy 73.9648 -72.6948) (xy 73.9648 -72.8472) (xy 73.3552 -72.8472) (xy 73.3552 -72.6948)
				)
			)
		)
	)
	(footprint ""
		(layer "B.Cu")
		(at 18.415 -80.137)
		(property "Reference" "R473"
			(at 3.81 0.29337 0)
			(unlocked yes)
			(layer "B.SilkS")
			(effects
				(font
					(size 0.7874 0.5842)
					(thickness 0.1524)
				)
				(justify mirror)
			)
		)
		(property "Value" "VAL*"
			(at -0.02032 2.13233 0)
			(unlocked yes)
			(layer "B.Fab")
			(hide yes)
			(effects
				(font
					(size 0.7874 0.5842)
					(thickness 0.1524)
				)
				(justify mirror)
			)
		)
		(property "Tolerance" "TOL*"
			(at -0.044704 3.05435 0)
			(unlocked yes)
			(layer "Cmts.User")
			(hide yes)
			(effects
				(font
					(size 0.7874 0.5842)
					(thickness 0.1524)
				)
				(justify mirror)
			)
		)
		(property "User Part Number" "PARTNUM*"
			(at -0.02032 4.024884 0)
			(unlocked yes)
			(layer "Cmts.User")
			(hide yes)
			(effects
				(font
					(size 0.7874 0.5842)
					(thickness 0.1524)
				)
				(justify mirror)
			)
		)
		(property "Device Type" "RESISTOR-G155-100R0-J0,0OHM,-"
			(at -0.008382 1.210564 0)
			(unlocked yes)
			(layer "B.Fab")
			(hide yes)
			(effects
				(font
					(size 0.7874 0.5842)
					(thickness 0.1524)
				)
				(justify mirror)
			)
		)
		(duplicate_pad_numbers_are_jumpers no)
		(fp_line
			(start -1.143 -0.5588)
			(end 1.143 -0.5588)
			(stroke
				(width 0.1)
				(type default)
			)
			(layer "B.SilkS")
		)
		(fp_line
			(start -1.143 0.5588)
			(end -1.143 -0.5588)
			(stroke
				(width 0.1)
				(type default)
			)
			(layer "B.SilkS")
		)
		(fp_line
			(start 1.143 -0.5588)
			(end 1.143 0.5588)
			(stroke
				(width 0.1)
				(type default)
			)
			(layer "B.SilkS")
		)
		(fp_line
			(start 1.143 0.5588)
			(end -1.143 0.5588)
			(stroke
				(width 0.1)
				(type default)
			)
			(layer "B.SilkS")
		)
		(fp_poly
			(pts
				(xy 1.143 0.5588) (xy -1.143 0.5588) (xy -1.143 -0.5588) (xy 1.143 -0.5588)
			)
			(stroke
				(width 0)
				(type default)
			)
			(fill no)
			(layer "B.CrtYd")
		)
		(fp_line
			(start -0.508 -0.3048)
			(end 0.508 -0.3048)
			(stroke
				(width 0.1)
				(type default)
			)
			(layer "B.Fab")
		)
		(fp_line
			(start -0.508 0.3048)
			(end -0.508 -0.3048)
			(stroke
				(width 0.1)
				(type default)
			)
			(layer "B.Fab")
		)
		(fp_line
			(start 0.508 -0.3048)
			(end 0.508 0.3048)
			(stroke
				(width 0.1)
				(type default)
			)
			(layer "B.Fab")
		)
		(fp_line
			(start 0.508 0.3048)
			(end -0.508 0.3048)
			(stroke
				(width 0.1)
				(type default)
			)
			(layer "B.Fab")
		)
		(pad "1" smd rect
			(at 0.5334 0 180)
			(size 0.7112 0.6096)
			(layers "B.Cu" "B.Mask" "B.Paste")
			(net "R_FT4232_I2C_SDA_IN")
		)
		(pad "2" smd rect
			(at -0.5334 0 180)
			(size 0.7112 0.6096)
			(layers "B.Cu" "B.Mask" "B.Paste")
			(net "FT4232_I2C_SDA")
		)
		(zone
			(layer "B.Cu")
			(hatch none 0.5)
			(connect_pads
				(clearance 0)
			)
			(min_thickness 0.25)
			(keepout
				(tracks not_allowed)
				(vias allowed)
				(pads allowed)
				(copperpour not_allowed)
				(footprints allowed)
			)
			(placement
				(enabled no)
				(sheetname "")
			)
			(fill
				(thermal_gap 0.5)
				(thermal_bridge_width 0.5)
				(island_removal_mode 0)
			)
			(polygon
				(pts
					(xy 18.4912 -79.8322) (xy 18.4912 -80.4418) (xy 18.3388 -80.4418) (xy 18.3388 -79.8322)
				)
			)
		)
		(zone
			(layer "B.Cu")
			(hatch none 0.5)
			(connect_pads
				(clearance 0)
			)
			(min_thickness 0.25)
			(keepout
				(tracks allowed)
				(vias not_allowed)
				(pads allowed)
				(copperpour not_allowed)
				(footprints allowed)
			)
			(placement
				(enabled no)
				(sheetname "")
			)
			(fill
				(thermal_gap 0.5)
				(thermal_bridge_width 0.5)
				(island_removal_mode 0)
			)
			(polygon
				(pts
					(xy 18.4912 -79.8322) (xy 18.4912 -80.4418) (xy 18.3388 -80.4418) (xy 18.3388 -79.8322)
				)
			)
		)
	)
)
